FILE_TYPE = MACRO_DRAWING;
SET COLOR_WIRE YELLOW;
SET COLOR_PROP MONO;
SET COLOR_DOT WHITE;
SET COLOR_ARC YELLOW;
SET COLOR_BODY GREEN;
SET COLOR_NOTE MONO;
SET PROP_DISPLAY VALUE;
SET PAGE_NUMBER P10;
FORCEADD INTEL_CORP_BPAGE..1
(4250 200);
FORCEPROP 1 LAST CUSTOM_TXT_CDS <CURRENT_DESIGN_SHEET> OF <TOTAL_DESIGN_SHEETS>
J 0
(3750 225);
PAINT GREEN (3750 225);
FORCEPROP 1 LAST CUSTOM_TXT_CDS <CON_LAST_MODIFIED>
J 0
(2325 550);
PAINT GREEN (2325 550);
FORCEPROP 2 LAST CUSTOM_TXT_CDS <XR_PAGE_TITLE>
J 0
(-3640 5450);
DISPLAY 0.638298 (-3640 5450);
PAINT PINK (-3640 5450);
DISPLAY INVISIBLE (-3640 5450);
FORCEPROP 1 LAST SCH_ADDRESS3 Santa Clara, CA 95052-8119
J 0
(275 225);
DISPLAY 0.617021 (275 225);
PAINT GREEN (275 225);
FORCEPROP 1 LAST SCH_ADDRESS2 P.O. BOX 58119
J 0
(275 275);
DISPLAY 0.617021 (275 275);
PAINT GREEN (275 275);
FORCEPROP 1 LAST SCH_ADDRESS1 2200 Mission College Blvd.
J 0
(275 325);
DISPLAY 0.617021 (275 325);
PAINT GREEN (275 325);
FORCEPROP 1 LAST SCH_TITLE INTERRUPTS AND ERROR PROPAGATION
J 0
(-3700 250);
DISPLAY 1.212766 (-3700 250);
PAINT ORANGE (-3700 250);
FORCEPROP 1 LAST SCH_NUMBER H4694802
J 0
(2950 350);
DISPLAY 1.212766 (2950 350);
PAINT YELLOW (2950 350);
FORCEPROP 1 LAST SCH_DEPT BESD
J 1
(-200 300);
DISPLAY 1.212766 (-200 300);
PAINT YELLOW (-200 300);
FORCEPROP 1 LAST SCH_REV 2.420
J 0
(4000 350);
DISPLAY 0.978723 (4000 350);
PAINT YELLOW (4000 350);
FORCEPROP 2 LAST CDS_LIB mstr_symbols
J 0
(4250 200);
PAINT MONO (4250 200);
DISPLAY INVISIBLE (4250 200);
FORCEPROP 2 LAST PAGE_BORDER TRUE
J 0
(-3640 5450);
DISPLAY 0.638298 (-3640 5450);
PAINT PINK (-3640 5450);
DISPLAY INVISIBLE (-3640 5450);
FORCEPROP 1 LAST COMMENT_BODY TRUE
J 0
(4262 212);
DISPLAY 0.468085 (4262 212);
PAINT GREEN (4262 212);
DISPLAY INVISIBLE (4262 212);
FORCEPROP 1 LAST CDS_CON_LAST_MODIFIED Tue Dec 01 11:47:57 2015
J 0
(2825 525);
PAINT ORANGE (2825 525);
DISPLAY INVISIBLE (2825 525);
FORCEPROP 2 LAST CDS_XR_PAGE_TITLE CR-10 : @BASEBOARD_FAB2_LIB.BASEBOARD_FAB2(SCH_1):PAGE10
J 0
(-3640 5450);
DISPLAY 0.638298 (-3640 5450);
PAINT PINK (-3640 5450);
DISPLAY INVISIBLE (-3640 5450);
FORCENOTE
$CDS_IMAGE|010_Interrupts_and_Error.jpg|5326|4270
(-325 2925) 0;
DISPLAY CENTER (-325 2925);
PAINT MONO (-325 2925);
QUIT
